# BASEBOARD_FAB2 (Tioga Pass) — schematic parts with pin connectivity, parts 1664–1837 of 4751; source: Cadence DE-HDL packaged netlist (pstxprt.dat, pstxnet.dat, pstchip.dat)

C8E12  CAP  0.1UF 25V 10% X7R  pkg 0603LF  page 240 : 1 = VR_P3V3_STBY_PHASE ; 2 = VR_P3V3_STBY_BOOT_R
C8E13  CAP  1000PF 50V 10% EMPTY  pkg 0402LF  page 241 : 1 = PWRGD_P12V_HSC_DLY ; 2 = AGND_P5V_STBY
C8E14  CAP  1.0UF 16V 10% X6S  pkg 0402  page 240 : 1 = VR_FET_SW_P12V_STBY_P3V3_STBY ; 2 = GND
C8E15  CAP  0.022UF 16V 10% X7R  pkg 0402LF  page 241 : 1 = VR_P5V_STBY_SS ; 2 = AGND_P5V_STBY
C8E16  CAP  270PF 50V 10% X7R  pkg 0402LF  page 241 : 1 = VR_P5V_STBY_COMP ; 2 = AGND_P5V_STBY
C8E17  CAP  1000PF 50V 10% EMPTY  pkg 0402LF  page 240 : 1 = PWRGD_P5V_STBY ; 2 = AGND_P3V3_STBY
C8E18  CAP_A  0.1UF 16V 10% X7R  pkg 0402V  page 154 : 1 = P3V3_STBY ; 2 = GND
C8E19  CAP_A  0.1UF 16V 10% X7R  pkg 0402V  page 198 : 1 = P5V_STBY ; 2 = GND
C8F1  CAP  2200PF 50V 10% X7R  pkg 0402LF  page 241 : 1 = VR_P5V_STBY_RC_COMP ; 2 = AGND_P5V_STBY
C8F2  CAP  1000PF 50V 10% X7R  pkg 0402LF  page 240 : 1 = PWRGD_P3V3_STBY_R ; 2 = GND
C8F3  CAP  3300PF 50V 10% EMPTY  pkg 0402LF  page 240 : 1 = VR_P3V3_STBY_PHASE ; 2 = VR_P3V3_STBY_SNUB
C8F4  CAP_A  1.0UF 6.3V 10% X6S  pkg 0402V  page 162 : 1 = P3V3_STBY ; 2 = GND
C8F5  CAP_A  0.01UF 25V 10% X7R  pkg 0402V  page 162 : 1 = P3V3_STBY ; 2 = GND
C8F6  CAP_A  0.01UF 25V 10% X7R  pkg 0402V  page 185 : 1 = SATA6G_S0_TX_DP ; 2 = P3E_PCH_M2_SATA6G_TX_R_DP
C8F7  CAP  0.22UF 16V 10% X7R  pkg 0402  page 185 : 1 = P3E_PCH_TX_0_DP ; 2 = P3E_PCH_M2_SATA6G_TX_R_DP
C8F8  ST470U6D3VDM-7-GP  IRP=1.7A  pkg SMD-TCG4  page 240 : 1 = P3V3_STBY ; 2 = GND
C8F11  CAP_A  0.01UF 25V 10% X7R  pkg 0402V  page 185 : 1 = SATA6G_S0_TX_DN ; 2 = P3E_PCH_M2_SATA6G_TX_R_DN
C8F12  CAP  0.22UF 16V 10% X7R  pkg 0402  page 185 : 1 = P3E_PCH_TX_0_DN ; 2 = P3E_PCH_M2_SATA6G_TX_R_DN
C8F13  CAP_A  0.01UF 25V 10% X7R  pkg 0402V  page 185 : 1 = SATA6G_S0_RX_DP ; 2 = P3E_PCH_M2_SATA6G_RX_R_DP
C8F14  ST470U6D3VDM-7-GP  IRP=1.7A  pkg SMD-TCG4  page 240 : 1 = P3V3_STBY ; 2 = GND
C8F15  CAP_A  0.01UF 25V 10% X7R  pkg 0402V  page 185 : 1 = SATA6G_S0_RX_DN ; 2 = P3E_PCH_M2_SATA6G_RX_R_DN
C8F16  CAP_A  0.1UF 16V 10% X7R  pkg 0402V  page 156 : 1 = P3V3_STBY ; 2 = GND
C8F17  CAP_A  0.1UF 16V 10% X7R  pkg 0402V  page 198 : 1 = P5V_STBY ; 2 = GND
C8F18  CAP  15.0PF 50V 5% COG  pkg 0402LF  page 101 : 1 = XTAL_CK_MNG_IN ; 2 = GND
C8F19  CAP  15.0PF 50V 5% COG  pkg 0402LF  page 101 : 1 = XTAL_CK_MNG_OUT ; 2 = GND
C8G1  CAP  0.22UF 16V 10% X7R  pkg 0402  page 105 : 1 = P3E_CPU0_PE2_SS_TXP<4> ; 2 = P3E_CPU0_PE2_SS_C_TXP<4>
C8G2  CAP  0.22UF 16V 10% X7R  pkg 0402  page 105 : 1 = P3E_CPU0_PE2_SS_TXN<4> ; 2 = P3E_CPU0_PE2_SS_C_TXN<4>
C8G3  CAP  0.22UF 16V 10% X7R  pkg 0402  page 105 : 1 = P3E_CPU0_PE2_SS_TXP<3> ; 2 = P3E_CPU0_PE2_SS_C_TXP<3>
C8G4  CAP  0.22UF 16V 10% X7R  pkg 0402  page 105 : 1 = P3E_CPU0_PE2_SS_TXN<3> ; 2 = P3E_CPU0_PE2_SS_C_TXN<3>
C8G5  CAP  0.22UF 16V 10% X7R  pkg 0402  page 105 : 1 = P3E_CPU0_PE2_SS_TXP<2> ; 2 = P3E_CPU0_PE2_SS_C_TXP<2>
C8G6  CAP  0.22UF 16V 10% X7R  pkg 0402  page 105 : 1 = P3E_CPU0_PE2_SS_TXN<2> ; 2 = P3E_CPU0_PE2_SS_C_TXN<2>
C8G7  CAP  0.22UF 16V 10% X7R  pkg 0402  page 105 : 1 = P3E_CPU0_PE2_SS_TXN<1> ; 2 = P3E_CPU0_PE2_SS_C_TXN<1>
C8G8  CAP  0.22UF 16V 10% X7R  pkg 0402  page 105 : 1 = P3E_CPU0_PE2_SS_TXP<1> ; 2 = P3E_CPU0_PE2_SS_C_TXP<1>
C8G9  CAP  0.22UF 16V 10% X7R  pkg 0402  page 105 : 1 = P3E_CPU0_PE2_SS_TXP<0> ; 2 = P3E_CPU0_PE2_SS_C_TXP<0>
C8G10  CAP  0.22UF 16V 10% X7R  pkg 0402  page 105 : 1 = P3E_CPU0_PE2_SS_TXN<0> ; 2 = P3E_CPU0_PE2_SS_C_TXN<0>
C8L1  CAP  100UF 4V 20% X5R  pkg 0805  page 228 : 1 = PVDDQ_KLM ; 2 = GND
C8L2  CAP  100UF 4V 20% X5R  pkg 0805  page 228 : 1 = PVDDQ_KLM ; 2 = GND
C8L3  CAP  100UF 4V 20% X5R  pkg 0805  page 230 : 1 = PVTT_KLM ; 2 = GND
C8L4  CAP  100UF 4V 20% X5R  pkg 0805  page 230 : 1 = PVTT_KLM ; 2 = GND
C8L5  CAP_A  47UF 4V 20% X5R  pkg 0603V  page 228 : 1 = PVDDQ_KLM ; 2 = GND
C8L6  CAP_A  47UF 4V 20% X5R  pkg 0603V  page 228 : 1 = PVDDQ_KLM ; 2 = GND
C8L7  CAP_A  47UF 4V 20% X5R  pkg 0603V  page 228 : 1 = PVDDQ_KLM ; 2 = GND
C8L8  CAP_A  47UF 4V 20% X5R  pkg 0603V  page 228 : 1 = PVDDQ_KLM ; 2 = GND
C8L9  CAP_A  47UF 4V 20% X5R  pkg 0603V  page 228 : 1 = PVDDQ_KLM ; 2 = GND
C8L10  CAP_A  47UF 4V 20% X5R  pkg 0603V  page 228 : 1 = PVDDQ_KLM ; 2 = GND
C8L11  CAP  100UF 4V 20% X5R  pkg 0805  page 228 : 1 = PVDDQ_KLM ; 2 = GND
C8L12  CAP_A  47UF 4V 20% X5R  pkg 0603V  page 228 : 1 = PVDDQ_KLM ; 2 = GND
C8M1  CAP_A  47UF 4V 20% X5R  pkg 0603V  page 228 : 1 = PVDDQ_KLM ; 2 = GND
C8M2  CAP_A  47UF 4V 20% X5R  pkg 0603V  page 228 : 1 = PVDDQ_KLM ; 2 = GND
C8M3  CAP_A  47UF 4V 20% X5R  pkg 0603V  page 228 : 1 = PVDDQ_KLM ; 2 = GND
C8M4  CAP_A  47UF 4V 20% X5R  pkg 0603V  page 228 : 1 = PVDDQ_KLM ; 2 = GND
C8M5  CAP_A  47UF 4V 20% X5R  pkg 0603V  page 228 : 1 = PVDDQ_KLM ; 2 = GND
C8M6  CAP_A  47UF 4V 20% X5R  pkg 0603V  page 228 : 1 = PVDDQ_KLM ; 2 = GND
C8M7  CAP  100UF 4V 20% X5R  pkg 0805  page 228 : 1 = PVDDQ_KLM ; 2 = GND
C8M8  CAP_A  47UF 4V 20% X5R  pkg 0603V  page 228 : 1 = PVDDQ_KLM ; 2 = GND
C8M9  CAP_A  47UF 4V 20% X5R  pkg 0603V  page 228 : 1 = PVDDQ_KLM ; 2 = GND
C8M10  CAP_A  47UF 4V 20% X5R  pkg 0603V  page 228 : 1 = PVDDQ_KLM ; 2 = GND
C8M11  CAP  100UF 4V 20% X5R  pkg 0805  page 228 : 1 = PVDDQ_KLM ; 2 = GND
C8M12  CAP_A  47UF 4V 20% X5R  pkg 0603V  page 230 : 1 = PVTT_KLM ; 2 = GND
C8P1  CAP  100UF 4V 20% X5R  pkg 0805  page 228 : 1 = PVDDQ_KLM ; 2 = GND
C8P2  CAP  100UF 4V 20% X5R  pkg 0805  page 228 : 1 = PVDDQ_KLM ; 2 = GND
C8P3  CAP  100UF 4V 20% X5R  pkg 0805  page 228 : 1 = PVDDQ_KLM ; 2 = GND
C8P4  CAP  100UF 4V 20% X5R  pkg 0805  page 228 : 1 = PVDDQ_KLM ; 2 = GND
C8P5  CAP  22UF 4V 20% X6S  pkg 0805LF  page 76 : 1 = PVSA_CPU1 ; 2 = GND
C8P6  CAP  22UF 4V 20% X6S  pkg 0805LF  page 76 : 1 = PVSA_CPU1 ; 2 = GND
C8P7  CAP  22UF 4V 20% X6S  pkg 0805LF  page 76 : 1 = PVSA_CPU1 ; 2 = GND
C8P8  CAP  100UF 4V 20% X5R  pkg 0805  page 76 : 1 = PVCCMCP_CPU1 ; 2 = GND
C8P9  CAP  100UF 4V 20% X5R  pkg 0805  page 76 : 1 = PVCCMCP_CPU1 ; 2 = GND
C8P10  CAP  47UF 4V 20% X6S  pkg 0805  page 76 : 1 = PVCCIN_CPU1 ; 2 = GND
C8P11  CAP  47UF 4V 20% X6S  pkg 0805  page 76 : 1 = PVCCIN_CPU1 ; 2 = GND
C8P12  CAP  47UF 4V 20% X6S  pkg 0805  page 76 : 1 = PVCCIN_CPU1 ; 2 = GND
C8P13  CAP  47UF 4V 20% X6S  pkg 0805  page 76 : 1 = PVCCIN_CPU1 ; 2 = GND
C8P14  CAP  100UF 4V 20% X5R  pkg 0805  page 76 : 1 = PVCCMCP_CPU1 ; 2 = GND
C8P15  CAP  100UF 4V 20% X5R  pkg 0805  page 76 : 1 = PVCCMCP_CPU1 ; 2 = GND
C8P16  CAP  47UF 4V 20% X6S  pkg 0805  page 76 : 1 = PVCCIN_CPU1 ; 2 = GND
C8P17  CAP  47UF 4V 20% X6S  pkg 0805  page 76 : 1 = PVCCIN_CPU1 ; 2 = GND
C8P18  CAP  47UF 4V 20% X6S  pkg 0805  page 76 : 1 = PVCCIN_CPU1 ; 2 = GND
C8P19  CAP  47UF 4V 20% X6S  pkg 0805  page 76 : 1 = PVCCIN_CPU1 ; 2 = GND
C8P20  CAP  47UF 4V 20% X6S  pkg 0805  page 76 : 1 = PVCCIN_CPU1 ; 2 = GND
C8P21  CAP  47UF 4V 20% X6S  pkg 0805  page 76 : 1 = PVCCIN_CPU1 ; 2 = GND
C8P22  CAP  100UF 4V 20% X5R  pkg 0805  page 76 : 1 = PVCCMCP_CPU1 ; 2 = GND
C8P23  CAP  100UF 4V 20% X5R  pkg 0805  page 76 : 1 = PVCCMCP_CPU1 ; 2 = GND
C8P24  CAP  47UF 4V 20% X6S  pkg 0805  page 76 : 1 = PVCCIN_CPU1 ; 2 = GND
C8P25  CAP  47UF 4V 20% X6S  pkg 0805  page 76 : 1 = PVCCIN_CPU1 ; 2 = GND
C8P26  CAP  47UF 4V 20% X6S  pkg 0805  page 76 : 1 = PVCCIN_CPU1 ; 2 = GND
C8P27  CAP  47UF 4V 20% X6S  pkg 0805  page 76 : 1 = PVCCIN_CPU1 ; 2 = GND
C8P28  CAP  47UF 4V 20% X6S  pkg 0805  page 76 : 1 = PVCCIN_CPU1 ; 2 = GND
C8P29  CAP  47UF 4V 20% X6S  pkg 0805  page 76 : 1 = PVCCIN_CPU1 ; 2 = GND
C8P30  CAP  100UF 4V 20% X5R  pkg 0805  page 225 : 1 = PVDDQ_GHJ ; 2 = GND
C8P31  CAP  100UF 4V 20% X5R  pkg 0805  page 225 : 1 = PVDDQ_GHJ ; 2 = GND
C8P32  CAP  100UF 4V 20% X5R  pkg 0805  page 225 : 1 = PVDDQ_GHJ ; 2 = GND
C8P33  CAP  100UF 4V 20% X5R  pkg 0805  page 225 : 1 = PVDDQ_GHJ ; 2 = GND
C8P34  CAP  100UF 4V 20% X5R  pkg 0805  page 225 : 1 = PVDDQ_GHJ ; 2 = GND
C8T1  CAP_A  47UF 4V 20% X5R  pkg 0603V  page 225 : 1 = PVDDQ_GHJ ; 2 = GND
C8T2  CAP_A  47UF 4V 20% X5R  pkg 0603V  page 225 : 1 = PVDDQ_GHJ ; 2 = GND
C8T3  CAP  100UF 4V 20% X5R  pkg 0805  page 229 : 1 = PVTT_GHJ ; 2 = GND
C8T4  CAP_A  47UF 4V 20% X5R  pkg 0603V  page 225 : 1 = PVDDQ_GHJ ; 2 = GND
C8T5  CAP_A  47UF 4V 20% X5R  pkg 0603V  page 225 : 1 = PVDDQ_GHJ ; 2 = GND
C8T6  CAP_A  47UF 4V 20% X5R  pkg 0603V  page 225 : 1 = PVDDQ_GHJ ; 2 = GND
C8T7  CAP_A  47UF 4V 20% X5R  pkg 0603V  page 225 : 1 = PVDDQ_GHJ ; 2 = GND
C8T8  CAP_A  47UF 4V 20% X5R  pkg 0603V  page 225 : 1 = PVDDQ_GHJ ; 2 = GND
C8T9  CAP_A  47UF 4V 20% X5R  pkg 0603V  page 225 : 1 = PVDDQ_GHJ ; 2 = GND
C8T10  CAP_A  47UF 4V 20% X5R  pkg 0603V  page 225 : 1 = PVDDQ_GHJ ; 2 = GND
C8T11  CAP_A  47UF 4V 20% X5R  pkg 0603V  page 225 : 1 = PVDDQ_GHJ ; 2 = GND
C8U1  CAP  100UF 4V 20% X5R  pkg 0805  page 225 : 1 = PVDDQ_GHJ ; 2 = GND
C8U2  CAP_A  47UF 4V 20% X5R  pkg 0603V  page 225 : 1 = PVDDQ_GHJ ; 2 = GND
C8U3  CAP_A  47UF 4V 20% X5R  pkg 0603V  page 225 : 1 = PVDDQ_GHJ ; 2 = GND
C8U4  CAP_A  47UF 4V 20% X5R  pkg 0603V  page 225 : 1 = PVDDQ_GHJ ; 2 = GND
C8U5  CAP_A  47UF 4V 20% X5R  pkg 0603V  page 225 : 1 = PVDDQ_GHJ ; 2 = GND
C8U6  CAP_A  47UF 4V 20% X5R  pkg 0603V  page 225 : 1 = PVDDQ_GHJ ; 2 = GND
C8U7  CAP_A  47UF 4V 20% X5R  pkg 0603V  page 225 : 1 = PVDDQ_GHJ ; 2 = GND
C8U8  CAP  100UF 4V 20% X5R  pkg 0805  page 225 : 1 = PVDDQ_GHJ ; 2 = GND
C8U9  CAP_A  47UF 4V 20% X5R  pkg 0603V  page 225 : 1 = PVDDQ_GHJ ; 2 = GND
C8U10  CAP  100UF 4V 20% X5R  pkg 0805  page 229 : 1 = PVTT_GHJ ; 2 = GND
C8U11  CAP  100UF 4V 20% X5R  pkg 0805  page 225 : 1 = PVDDQ_GHJ ; 2 = GND
C8U12  CAP  100UF 4V 20% X5R  pkg 0805  page 225 : 1 = PVDDQ_GHJ ; 2 = GND
C8U13  CAP_A  47UF 4V 20% X5R  pkg 0603V  page 225 : 1 = PVDDQ_GHJ ; 2 = GND
C8W1  SC1U16V3KX-2GP  10%  pkg SMD-BCG  page 249 : 1 = BMC_SELF_HW_D_RST ; 2 = BMC_TPM_HW_C_RST
C8W2  CAP_A  0.1UF 16V 10% X7R  pkg 0402V  page 249 : 1 = P5V_STBY ; 2 = GND
C8W3  CAP  100UF 4V 20% X5R  pkg 0805  page 42 : 1 = PVCCIN_CPU0 ; 2 = GND
C8W4  CAP  100UF 4V 20% X5R  pkg 0805  page 76 : 1 = PVCCIN_CPU1 ; 2 = GND
C8W5  CAP_A  1.0UF 6.3V 10% X6S  pkg 0402V  page 245 : 1 = P3V3_STBY ; 2 = GND
C8W6  CAP_A  0.01UF 25V 10% X7R  pkg 0402V  page 245 : 1 = P3V3_STBY ; 2 = GND
C9A1  CAP_A  0.1UF 16V 10% X7R  pkg 0402V  page 155 : 1 = P5V_STBY_DGB_FS ; 2 = GND
C9A2  CAP_A  0.1UF 16V 10% X7R  pkg 0402V  page 111 : 1 = XDP_SYSPWROK ; 2 = GND
C9A3  CAP_A  0.1UF 16V 10% X7R  pkg 0402V  page 175 : 1 = P3V3_STBY ; 2 = GND
C9A4  CAP_A  0.1UF 16V 10% X7R  pkg 0402V  page 111 : 1 = XDP_CPU_PWR_DEBUG_N ; 2 = GND
C9A5  CAP_A  0.1UF 16V 10% X7R  pkg 0402V  page 111 : 1 = XDP_RST_CO_N ; 2 = GND
C9A6  CAP_A  1.0UF 6.3V 10% X6S  pkg 0402V  page 111 : 1 = P1V05_PCH_STBY ; 2 = GND
C9B1  CAP  10UF 16V 10% X6S  pkg 0805  page 172 : 1 = P5V_HDD_SATA ; 2 = GND
C9B2  CAP  10UF 16V 10% X6S  pkg 0805  page 172 : 1 = P12V_HDD_SATA ; 2 = GND
C9B7  CAP_A  0.1UF 16V 10% X7R  pkg 0402V  page 167 : 1 = P3V3_STBY ; 2 = GND
C9B8  CAPP  330UF 10V 20% POSCAP  pkg 7343HLF  page 176 : 1 = P5V_USB ; 2 = GND
C9B9  SC1U10V2KX-4-GP  10%  pkg SMD-BCG6  page 186 : 1 = P5V_STBY ; 2 = GND
C9B10  CAP_A  0.1UF 16V 10% X7R  pkg 0402V  page 186 : 1 = P5V_STBY ; 2 = GND
C9E1  CAP_A  22.0UF 4V 20% EMPTY  pkg 0603V  page 139 : 1 = P0V9_LAN ; 2 = GND
C9E4  CAP_A  0.1UF 16V 10% X7R  pkg 0402V  page 139 : 1 = PE_PCH_SPRV_RX_DP ; 2 = PE_PCH_SPRV_RX_C_DP
C9E5  CAP_A  0.1UF 16V 10% X7R  pkg 0402V  page 139 : 1 = PE_PCH_SPRV_RX_DN ; 2 = PE_PCH_SPRV_RX_C_DN
C9E6  SC22U16V5MX-4-GP  20%  pkg SMD-BCG5  page 139 : 1 = P1V5_LAN ; 2 = GND
C9E7  CAP  0.039UF 25V 10% X7R  pkg 0402LF  page 139 : 1 = A_CTOP ; 2 = A_CBOT
C9E8  CAP  15.0PF 50V 5% COG  pkg 0402LF  page 139 : 1 = XTAL_25MHZ_OUT_R ; 2 = GND
C9E9  CAP  15.0PF 50V 5% COG  pkg 0402LF  page 139 : 1 = XTAL_25MHZ_IN ; 2 = GND
C9E10  CAP  10UF 6.3V 20% X6S  pkg 0603  page 238 : 1 = P1V15_AUX_BMC ; 2 = GND
C9E11  CAP  1.0UF 16V 10% X6S  pkg 0402  page 238 : 1 = P3V3_STBY ; 2 = GND
C9E12  CAP_A  22.0UF 4V 20% EMPTY  pkg 0603V  page 139 : 1 = P0V9_LAN ; 2 = GND
C9F1  SC22U16V5MX-4-GP  20%  pkg SMD-BCG5  page 240 : 1 = VR_FET_SW_P12V_STBY_P3V3_STBY ; 2 = GND
C9F2  SC22U16V5MX-4-GP  20%  pkg SMD-BCG5  page 139 : 1 = P3V3_STBY ; 2 = GND
C9F3  CAP  10UF 6.3V 20% X6S  pkg 0603  page 238 : 1 = P3V3_STBY ; 2 = GND
C9F4  CAP  22UF 4V 20% X6S  pkg 0805LF  page 238 : 1 = P1V15_AUX_BMC ; 2 = GND
C9F5  CAP_A  0.1UF 16V 10% X7R  pkg 0402V  page 239 : 1 = P3V3_STBY ; 2 = GND
C9F6  CAP  1000PF 50V 10% EMPTY  pkg 0402LF  page 239 : 1 = PWRGD_P2V5_BMC_STBY ; 2 = GND
C9F8  CAP  1000PF 50V 10% X7R  pkg 0402LF  page 238 : 1 = PWRGD_P1V15_BMC_STBY_R ; 2 = GND
C9F9  CAP  1000PF 50V 10% EMPTY  pkg 0402LF  page 238 : 1 = PWRGD_P1V2_BMC_STBY ; 2 = GND
C9F10  CAP  1000PF 50V 10% X7R  pkg 0402LF  page 239 : 1 = PWRGD_P1V2_BMC_STBY_R ; 2 = GND
C9F13  CAP  22UF 4V 20% X6S  pkg 0805LF  page 239 : 1 = P1V2_AUX_BMC ; 2 = GND
C9F22  CAP  470PF 50V 10% X7R  pkg 0402LF  page 141 : 1 = LED_LAN_1_N ; 2 = GND
C9F23  CAP_A  0.1UF 16V 10% X7R  pkg 0402V  page 145 : 1 = P3V3_STBY ; 2 = GND
C9G1  CAP  470PF 50V 10% X7R  pkg 0402LF  page 141 : 1 = LED_LAN_2_N ; 2 = GND
C9G2  CAP  470PF 50V 10% X7R  pkg 0402LF  page 141 : 1 = P3V3_STBY ; 2 = GND
C9G3  CAP  470PF 50V 10% X7R  pkg 0402LF  page 141 : 1 = LED_LAN_0_N ; 2 = GND
C9G4  CAP_A  0.1UF 16V 10% X7R  pkg 0402V  page 141 : 1 = GND_LAN_TRCT1234_C ; 2 = GND
C9G5  CAP  1.0UF 16V 10% X7S  pkg 0402  page 141 : 1 = GND_LAN_TRCT1234_C ; 2 = GND
C9G6  CAP_A  0.1UF 16V 10% X7R  pkg 0402V  page 141 : 1 = GND_LAN_TRCT1234_C ; 2 = GND
C9G9  CAP  4700PF 50V 10% EMPTY  pkg 0402LF  page 141 : 1 = NIC_SER_P_MDI_3_DP ; 2 = NIC_MDI_MNG_RX_DP
C9G12  CAP  4700PF 50V 10% EMPTY  pkg 0402LF  page 141 : 1 = NIC_SER_N_MDI_3_DN ; 2 = NIC_MDI_MNG_RX_DN
C9G13  CAP  4700PF 50V 10% EMPTY  pkg 0402LF  page 141 : 1 = NIC_SET_N_MDI_2_DN ; 2 = NIC_MDI_MNG_TX_DN
C9G14  CAP  47.0PF 50V 5% COG  pkg 0402LF  page 169 : 1 = A_P3V3_SCALED ; 2 = GND
C9G15  CAP  47.0PF 50V 5% COG  pkg 0402LF  page 169 : 1 = A_P5V_SCALED ; 2 = GND
C9G16  CAP  4700PF 50V 10% EMPTY  pkg 0402LF  page 141 : 1 = NIC_SET_P_MDI_2_DP ; 2 = NIC_MDI_MNG_TX_DP
C9G17  CAP  47.0PF 50V 5% COG  pkg 0402LF  page 169 : 1 = A_P12V_STBY_SCALED ; 2 = GND
C9G18  CAP  47.0PF 50V 5% COG  pkg 0402LF  page 169 : 1 = A_PVNN_STBY_PCH_SENSOR ; 2 = GND
C9G20  CAP  47.0PF 50V 5% COG  pkg 0402LF  page 169 : 1 = A_P3V3_STBY_SCALED ; 2 = GND
C9G21  CAP  47.0PF 50V 5% COG  pkg 0402LF  page 169 : 1 = A_P5V_STBY_SCALED ; 2 = GND
C9G22  CAP  10.0PF 50V 5% COG  pkg 0402LF  page 169 : 1 = A_P3V_BAT_SCALED ; 2 = GND
